(kicad_pcb
	(version 20260206)
	(generator "pcbnew")
	(generator_version "10.0")
	(general
		(thickness 1.6)
		(legacy_teardrops no)
	)
	(paper "A4")
	(title_block
		(title "peb — Lightning_PEB_BRD.brd")
		(comment 1 "Lightning (Wiwynn / Facebook NVMe JBOF) / footprints 625-631 of 2563")
	)
	(layers
		(0 "F.Cu" signal "TOP")
		(4 "In1.Cu" signal "L2GND")
		(6 "In2.Cu" signal "L3")
		(8 "In3.Cu" signal "L4VCC")
		(10 "In4.Cu" signal "L5VCC")
		(12 "In5.Cu" signal "L6")
		(14 "In6.Cu" signal "L7GND")
		(2 "B.Cu" signal "BOTTOM")
		(9 "F.Adhes" user "F.Adhesive")
		(11 "B.Adhes" user "B.Adhesive")
		(13 "F.Paste" user "Package Geometry/Pastemask Top")
		(15 "B.Paste" user "Package Geometry/Pastemask Bottom")
		(5 "F.SilkS" user "Ref Des/Silkscreen Top")
		(7 "B.SilkS" user "Ref Des/Silkscreen Bottom")
		(1 "F.Mask" user "Board Geometry/Soldermask Top")
		(3 "B.Mask" user "Board Geometry/Soldermask Bottom")
		(17 "Dwgs.User" user "User.Drawings")
		(19 "Cmts.User" user "User.Comments")
		(21 "Eco1.User" user "User.Eco1")
		(23 "Eco2.User" user "User.Eco2")
		(25 "Edge.Cuts" user "Board Geometry/Outline")
		(27 "Margin" user)
		(31 "F.CrtYd" user "Package Geometry/Place Bound Top")
		(29 "B.CrtYd" user "Package Geometry/Place Bound Bottom")
		(35 "F.Fab" user "Ref Des/Assembly Top")
		(33 "B.Fab" user "Ref Des/Assembly Bottom")
	)
	(footprint ""
		(layer "F.Cu")
		(at 116.253768 -29.020516 -90)
		(property "Reference" "C133"
			(at 0 0 270)
			(layer "F.SilkS")
			(hide yes)
			(effects
				(font
					(size 1.27 1.27)
				)
			)
		)
		(property "Value" "SCD1U10V2KX-5GP"
			(at 1.1811 -2.7051 270)
			(unlocked yes)
			(layer "F.Fab")
			(hide yes)
			(effects
				(font
					(size 1.016 1.016)
					(thickness 0.1524)
				)
			)
		)
		(property "Device Type" "C402H22"
			(at 1.1811 -4.2291 270)
			(unlocked yes)
			(layer "F.Fab")
			(hide yes)
			(effects
				(font
					(size 1.016 1.016)
					(thickness 0.1524)
				)
			)
		)
		(duplicate_pad_numbers_are_jumpers no)
		(fp_rect
			(start -0.4318 0.9525)
			(end 0.4318 -0.9525)
			(stroke
				(width 0)
				(type default)
			)
			(fill no)
			(layer "F.CrtYd")
		)
		(fp_rect
			(start -0.4318 0.9525)
			(end 0.4318 -0.9525)
			(stroke
				(width 0)
				(type default)
			)
			(fill no)
			(layer "F.Fab")
		)
		(pad "1" smd custom
			(at 0 -0.4445 270)
			(size 0.1524 0.1524)
			(layers "F.Cu" "F.Mask" "F.Paste")
			(net "P3V3_STBY")
			(options
				(clearance outline)
				(anchor circle)
			)
			(primitives
				(gr_poly
					(pts
						(arc
							(start 0.3048 -0.2032)
							(mid 0.275042 -0.275042)
							(end 0.2032 -0.3048)
						)
						(arc
							(start -0.2032 -0.3048)
							(mid -0.275042 -0.275042)
							(end -0.3048 -0.2032)
						)
						(arc
							(start -0.3048 0.2032)
							(mid -0.275042 0.275042)
							(end -0.2032 0.3048)
						)
						(arc
							(start 0.2032 0.3048)
							(mid 0.275042 0.275042)
							(end 0.3048 0.2032)
						)
					)
					(width 0)
					(fill yes)
				)
			)
		)
		(pad "2" smd custom
			(at 0 0.4445 270)
			(size 0.1524 0.1524)
			(layers "F.Cu" "F.Mask" "F.Paste")
			(net "GND")
			(options
				(clearance outline)
				(anchor circle)
			)
			(primitives
				(gr_poly
					(pts
						(arc
							(start 0.3048 -0.2032)
							(mid 0.275042 -0.275042)
							(end 0.2032 -0.3048)
						)
						(arc
							(start -0.2032 -0.3048)
							(mid -0.275042 -0.275042)
							(end -0.3048 -0.2032)
						)
						(arc
							(start -0.3048 0.2032)
							(mid -0.275042 0.275042)
							(end -0.2032 0.3048)
						)
						(arc
							(start 0.2032 0.3048)
							(mid 0.275042 0.275042)
							(end 0.3048 0.2032)
						)
					)
					(width 0)
					(fill yes)
				)
			)
		)
	)
	(footprint ""
		(layer "F.Cu")
		(at 58.166 -133.985)
		(property "Reference" "R5765"
			(at 0 0 0)
			(layer "F.SilkS")
			(hide yes)
			(effects
				(font
					(size 1.27 1.27)
				)
			)
		)
		(property "Value" "1K8R2F-GP"
			(at 0.064008 -3.993896 0)
			(unlocked yes)
			(layer "F.Fab")
			(hide yes)
			(effects
				(font
					(size 1.016 1.016)
					(thickness 0.1524)
				)
			)
		)
		(property "Device Type" "R402H16"
			(at 0.064008 -5.517896 0)
			(unlocked yes)
			(layer "F.Fab")
			(hide yes)
			(effects
				(font
					(size 1.016 1.016)
					(thickness 0.1524)
				)
			)
		)
		(duplicate_pad_numbers_are_jumpers no)
		(fp_line
			(start -0.508 -0.9398)
			(end -0.508 0.9398)
			(stroke
				(width 0.1524)
				(type default)
			)
			(layer "F.SilkS")
		)
		(fp_line
			(start 0.508 -0.9398)
			(end -0.508 -0.9398)
			(stroke
				(width 0.1524)
				(type default)
			)
			(layer "F.SilkS")
		)
		(fp_rect
			(start -0.508 0.9398)
			(end 0.508 -0.9398)
			(stroke
				(width 0)
				(type default)
			)
			(fill no)
			(layer "F.CrtYd")
		)
		(fp_rect
			(start -0.508 0.9398)
			(end 0.508 -0.9398)
			(stroke
				(width 0)
				(type default)
			)
			(fill no)
			(layer "F.Fab")
		)
		(pad "1" smd custom
			(at 0 -0.4445)
			(size 0.1397 0.1397)
			(layers "F.Cu" "F.Mask" "F.Paste")
			(net "P1V8_STBY")
			(options
				(clearance outline)
				(anchor circle)
			)
			(primitives
				(gr_poly
					(pts
						(arc
							(start -0.1778 -0.2794)
							(mid -0.249642 -0.249642)
							(end -0.2794 -0.1778)
						)
						(arc
							(start -0.2794 0.1778)
							(mid -0.249642 0.249642)
							(end -0.1778 0.2794)
						)
						(arc
							(start 0.1778 0.2794)
							(mid 0.249642 0.249642)
							(end 0.2794 0.1778)
						)
						(arc
							(start 0.2794 -0.1778)
							(mid 0.249642 -0.249642)
							(end 0.1778 -0.2794)
						)
					)
					(width 0)
					(fill yes)
				)
			)
		)
		(pad "2" smd custom
			(at 0 0.4445)
			(size 0.1397 0.1397)
			(layers "F.Cu" "F.Mask" "F.Paste")
			(net "ADC_P1V8_STBY")
			(options
				(clearance outline)
				(anchor circle)
			)
			(primitives
				(gr_poly
					(pts
						(arc
							(start -0.1778 -0.2794)
							(mid -0.249642 -0.249642)
							(end -0.2794 -0.1778)
						)
						(arc
							(start -0.2794 0.1778)
							(mid -0.249642 0.249642)
							(end -0.1778 0.2794)
						)
						(arc
							(start 0.1778 0.2794)
							(mid 0.249642 0.249642)
							(end 0.2794 0.1778)
						)
						(arc
							(start 0.2794 -0.1778)
							(mid 0.249642 -0.249642)
							(end 0.1778 -0.2794)
						)
					)
					(width 0)
					(fill yes)
				)
			)
		)
	)
	(footprint ""
		(layer "F.Cu")
		(at 68.961 -32.004 -90)
		(property "Reference" "PR37"
			(at 0 0 270)
			(layer "F.SilkS")
			(hide yes)
			(effects
				(font
					(size 1.27 1.27)
				)
			)
		)
		(property "Value" "10KR2F-2-GP"
			(at 0.064008 -3.993896 270)
			(unlocked yes)
			(layer "F.Fab")
			(hide yes)
			(effects
				(font
					(size 1.016 1.016)
					(thickness 0.1524)
				)
			)
		)
		(property "Device Type" "R402H16"
			(at 0.064008 -5.517896 270)
			(unlocked yes)
			(layer "F.Fab")
			(hide yes)
			(effects
				(font
					(size 1.016 1.016)
					(thickness 0.1524)
				)
			)
		)
		(duplicate_pad_numbers_are_jumpers no)
		(fp_line
			(start -0.508 -0.9398)
			(end -0.508 0.9398)
			(stroke
				(width 0.1524)
				(type default)
			)
			(layer "F.SilkS")
		)
		(fp_line
			(start 0.508 -0.9398)
			(end -0.508 -0.9398)
			(stroke
				(width 0.1524)
				(type default)
			)
			(layer "F.SilkS")
		)
		(fp_rect
			(start -0.508 0.9398)
			(end 0.508 -0.9398)
			(stroke
				(width 0)
				(type default)
			)
			(fill no)
			(layer "F.CrtYd")
		)
		(fp_rect
			(start -0.508 0.9398)
			(end 0.508 -0.9398)
			(stroke
				(width 0)
				(type default)
			)
			(fill no)
			(layer "F.Fab")
		)
		(pad "1" smd custom
			(at 0 -0.4445 270)
			(size 0.1397 0.1397)
			(layers "F.Cu" "F.Mask" "F.Paste")
			(net "P3V3_STBY_VFB")
			(options
				(clearance outline)
				(anchor circle)
			)
			(primitives
				(gr_poly
					(pts
						(arc
							(start -0.1778 -0.2794)
							(mid -0.249642 -0.249642)
							(end -0.2794 -0.1778)
						)
						(arc
							(start -0.2794 0.1778)
							(mid -0.249642 0.249642)
							(end -0.1778 0.2794)
						)
						(arc
							(start 0.1778 0.2794)
							(mid 0.249642 0.249642)
							(end 0.2794 0.1778)
						)
						(arc
							(start 0.2794 -0.1778)
							(mid 0.249642 -0.249642)
							(end 0.1778 -0.2794)
						)
					)
					(width 0)
					(fill yes)
				)
			)
		)
		(pad "2" smd custom
			(at 0 0.4445 270)
			(size 0.1397 0.1397)
			(layers "F.Cu" "F.Mask" "F.Paste")
			(net "AGND_P3V3_STBY")
			(options
				(clearance outline)
				(anchor circle)
			)
			(primitives
				(gr_poly
					(pts
						(arc
							(start -0.1778 -0.2794)
							(mid -0.249642 -0.249642)
							(end -0.2794 -0.1778)
						)
						(arc
							(start -0.2794 0.1778)
							(mid -0.249642 0.249642)
							(end -0.1778 0.2794)
						)
						(arc
							(start 0.1778 0.2794)
							(mid 0.249642 0.249642)
							(end 0.2794 0.1778)
						)
						(arc
							(start 0.2794 -0.1778)
							(mid 0.249642 -0.249642)
							(end 0.1778 -0.2794)
						)
					)
					(width 0)
					(fill yes)
				)
			)
		)
	)
	(footprint ""
		(layer "F.Cu")
		(at 6.8072 -186.2836 -90)
		(property "Reference" "PR9006"
			(at 0 0 270)
			(layer "F.SilkS")
			(hide yes)
			(effects
				(font
					(size 1.27 1.27)
				)
			)
		)
		(property "Value" "0R2J-2-GP"
			(at 0.064008 -3.993896 270)
			(unlocked yes)
			(layer "F.Fab")
			(hide yes)
			(effects
				(font
					(size 1.016 1.016)
					(thickness 0.1524)
				)
			)
		)
		(property "Device Type" "R402H16"
			(at 0.064008 -5.517896 270)
			(unlocked yes)
			(layer "F.Fab")
			(hide yes)
			(effects
				(font
					(size 1.016 1.016)
					(thickness 0.1524)
				)
			)
		)
		(duplicate_pad_numbers_are_jumpers no)
		(fp_line
			(start -0.508 -0.9398)
			(end -0.508 0.9398)
			(stroke
				(width 0.1524)
				(type default)
			)
			(layer "F.SilkS")
		)
		(fp_line
			(start 0.508 -0.9398)
			(end -0.508 -0.9398)
			(stroke
				(width 0.1524)
				(type default)
			)
			(layer "F.SilkS")
		)
		(fp_rect
			(start -0.508 0.9398)
			(end 0.508 -0.9398)
			(stroke
				(width 0)
				(type default)
			)
			(fill no)
			(layer "F.CrtYd")
		)
		(fp_rect
			(start -0.508 0.9398)
			(end 0.508 -0.9398)
			(stroke
				(width 0)
				(type default)
			)
			(fill no)
			(layer "F.Fab")
		)
		(pad "1" smd custom
			(at 0 -0.4445 270)
			(size 0.1397 0.1397)
			(layers "F.Cu" "F.Mask" "F.Paste")
			(net "HSW_SDA_2")
			(options
				(clearance outline)
				(anchor circle)
			)
			(primitives
				(gr_poly
					(pts
						(arc
							(start -0.1778 -0.2794)
							(mid -0.249642 -0.249642)
							(end -0.2794 -0.1778)
						)
						(arc
							(start -0.2794 0.1778)
							(mid -0.249642 0.249642)
							(end -0.1778 0.2794)
						)
						(arc
							(start 0.1778 0.2794)
							(mid 0.249642 0.249642)
							(end 0.2794 0.1778)
						)
						(arc
							(start 0.2794 -0.1778)
							(mid 0.249642 -0.249642)
							(end 0.1778 -0.2794)
						)
					)
					(width 0)
					(fill yes)
				)
			)
		)
		(pad "2" smd custom
			(at 0 0.4445 270)
			(size 0.1397 0.1397)
			(layers "F.Cu" "F.Mask" "F.Paste")
			(net "BMC_I2C5_D_PEB_SDA")
			(options
				(clearance outline)
				(anchor circle)
			)
			(primitives
				(gr_poly
					(pts
						(arc
							(start -0.1778 -0.2794)
							(mid -0.249642 -0.249642)
							(end -0.2794 -0.1778)
						)
						(arc
							(start -0.2794 0.1778)
							(mid -0.249642 0.249642)
							(end -0.1778 0.2794)
						)
						(arc
							(start 0.1778 0.2794)
							(mid 0.249642 0.249642)
							(end 0.2794 0.1778)
						)
						(arc
							(start 0.2794 -0.1778)
							(mid 0.249642 -0.249642)
							(end 0.1778 -0.2794)
						)
					)
					(width 0)
					(fill yes)
				)
			)
		)
	)
	(footprint ""
		(layer "F.Cu")
		(at 227.457 -82.9564)
		(property "Reference" "U136"
			(at 0 0 0)
			(layer "F.SilkS")
			(hide yes)
			(effects
				(font
					(size 1.27 1.27)
				)
			)
		)
		(property "Value" "TMP75AIDGKR-GP"
			(at -0.1143 -9.1948 0)
			(unlocked yes)
			(layer "F.Fab")
			(hide yes)
			(effects
				(font
					(size 1.016 1.016)
					(thickness 0.1524)
				)
			)
		)
		(property "Device Type" "MSOP8-1H44"
			(at -0.1143 -10.795 0)
			(unlocked yes)
			(layer "F.Fab")
			(hide yes)
			(effects
				(font
					(size 1.016 1.016)
					(thickness 0.1524)
				)
			)
		)
		(duplicate_pad_numbers_are_jumpers no)
		(fp_line
			(start -1.9558 -1.016)
			(end -1.9558 1.016)
			(stroke
				(width 0.1524)
				(type default)
			)
			(layer "F.SilkS")
		)
		(fp_line
			(start -1.9558 -0.5461)
			(end -1.4478 -0.0381)
			(stroke
				(width 0.1524)
				(type default)
			)
			(layer "F.SilkS")
		)
		(fp_line
			(start -1.9558 1.016)
			(end 1.0795 1.016)
			(stroke
				(width 0.1524)
				(type default)
			)
			(layer "F.SilkS")
		)
		(fp_line
			(start -1.778 1.0922)
			(end -1.778 3.048)
			(stroke
				(width 0.508)
				(type default)
			)
			(layer "F.SilkS")
		)
		(fp_line
			(start -1.4478 -0.0381)
			(end -1.9558 0.4699)
			(stroke
				(width 0.1524)
				(type default)
			)
			(layer "F.SilkS")
		)
		(fp_line
			(start 1.0795 -1.016)
			(end -1.9558 -1.016)
			(stroke
				(width 0.1524)
				(type default)
			)
			(layer "F.SilkS")
		)
		(fp_line
			(start 1.0795 1.016)
			(end 1.0795 -1.016)
			(stroke
				(width 0.1524)
				(type default)
			)
			(layer "F.SilkS")
		)
		(fp_poly
			(pts
				(xy -1.1557 -1.016) (xy -1.1557 1.016) (xy 1.1557 1.016) (xy 1.1557 -1.016)
			)
			(stroke
				(width 0)
				(type default)
			)
			(fill yes)
			(layer "F.SilkS")
		)
		(fp_rect
			(start -1.4986 2.4511)
			(end 1.4986 -2.4511)
			(stroke
				(width 0)
				(type default)
			)
			(fill no)
			(layer "F.CrtYd")
		)
		(fp_poly
			(pts
				(xy -2.032 3.302) (xy -2.032 -3.302) (xy 2.032 -3.302) (xy 2.032 -2.1209) (xy 1.4986 -2.1209) (xy 1.4986 -2.4511)
				(xy -1.4986 -2.4511) (xy -1.4986 2.4511) (xy 1.4986 2.4511) (xy 1.4986 -2.1082) (xy 2.032 -2.1082)
				(xy 2.032 3.302)
			)
			(stroke
				(width 0)
				(type default)
			)
			(fill no)
			(layer "F.CrtYd")
		)
		(fp_rect
			(start -2.032 3.302)
			(end 2.032 -3.302)
			(stroke
				(width 0)
				(type default)
			)
			(fill no)
			(layer "F.Fab")
		)
		(pad "1" smd rect
			(at -0.97536 2.05486)
			(size 0.3556 1.524)
			(layers "F.Cu" "F.Mask" "F.Paste")
			(net "TEMP_3_SDA")
		)
		(pad "2" smd rect
			(at -0.32512 2.05486)
			(size 0.3556 1.524)
			(layers "F.Cu" "F.Mask" "F.Paste")
			(net "TEMP_3_SCL")
		)
		(pad "3" smd rect
			(at 0.32512 2.05486)
			(size 0.3556 1.524)
			(layers "F.Cu" "F.Mask" "F.Paste")
			(net "TEMP_3_ALERT")
		)
		(pad "4" smd rect
			(at 0.97536 2.05486)
			(size 0.3556 1.524)
			(layers "F.Cu" "F.Mask" "F.Paste")
			(net "GND")
		)
		(pad "5" smd rect
			(at 0.97536 -2.05486)
			(size 0.3556 1.524)
			(layers "F.Cu" "F.Mask" "F.Paste")
			(net "TEMP_3_A2")
		)
		(pad "6" smd rect
			(at 0.32512 -2.05486)
			(size 0.3556 1.524)
			(layers "F.Cu" "F.Mask" "F.Paste")
			(net "TEMP_3_A1")
		)
		(pad "7" smd rect
			(at -0.32512 -2.05486)
			(size 0.3556 1.524)
			(layers "F.Cu" "F.Mask" "F.Paste")
			(net "TEMP_3_A0")
		)
		(pad "8" smd rect
			(at -0.97536 -2.05486)
			(size 0.3556 1.524)
			(layers "F.Cu" "F.Mask" "F.Paste")
			(net "P3V3_STBY")
		)
	)
	(footprint ""
		(layer "F.Cu")
		(at 17.63268 -136.126474 90)
		(property "Reference" "R346"
			(at 0 0 90)
			(layer "F.SilkS")
			(hide yes)
			(effects
				(font
					(size 1.27 1.27)
				)
			)
		)
		(property "Value" "3K3R2F-2-GP"
			(at 0.064008 -3.993896 90)
			(unlocked yes)
			(layer "F.Fab")
			(hide yes)
			(effects
				(font
					(size 1.016 1.016)
					(thickness 0.1524)
				)
			)
		)
		(property "Device Type" "R402H16"
			(at 0.064008 -5.517896 90)
			(unlocked yes)
			(layer "F.Fab")
			(hide yes)
			(effects
				(font
					(size 1.016 1.016)
					(thickness 0.1524)
				)
			)
		)
		(duplicate_pad_numbers_are_jumpers no)
		(fp_line
			(start 0.508 -0.9398)
			(end -0.508 -0.9398)
			(stroke
				(width 0.1524)
				(type default)
			)
			(layer "F.SilkS")
		)
		(fp_line
			(start -0.508 -0.9398)
			(end -0.508 0.9398)
			(stroke
				(width 0.1524)
				(type default)
			)
			(layer "F.SilkS")
		)
		(fp_rect
			(start -0.508 0.9398)
			(end 0.508 -0.9398)
			(stroke
				(width 0)
				(type default)
			)
			(fill no)
			(layer "F.CrtYd")
		)
		(fp_rect
			(start -0.508 0.9398)
			(end 0.508 -0.9398)
			(stroke
				(width 0)
				(type default)
			)
			(fill no)
			(layer "F.Fab")
		)
		(pad "1" smd custom
			(at 0 -0.4445 90)
			(size 0.1397 0.1397)
			(layers "F.Cu" "F.Mask" "F.Paste")
			(net "P3V3_STBY")
			(options
				(clearance outline)
				(anchor circle)
			)
			(primitives
				(gr_poly
					(pts
						(arc
							(start -0.1778 -0.2794)
							(mid -0.249642 -0.249642)
							(end -0.2794 -0.1778)
						)
						(arc
							(start -0.2794 0.1778)
							(mid -0.249642 0.249642)
							(end -0.1778 0.2794)
						)
						(arc
							(start 0.1778 0.2794)
							(mid 0.249642 0.249642)
							(end 0.2794 0.1778)
						)
						(arc
							(start 0.2794 -0.1778)
							(mid 0.249642 -0.249642)
							(end 0.1778 -0.2794)
						)
					)
					(width 0)
					(fill yes)
				)
			)
		)
		(pad "2" smd custom
			(at 0 0.4445 90)
			(size 0.1397 0.1397)
			(layers "F.Cu" "F.Mask" "F.Paste")
			(net "ROMD1_R")
			(options
				(clearance outline)
				(anchor circle)
			)
			(primitives
				(gr_poly
					(pts
						(arc
							(start -0.1778 -0.2794)
							(mid -0.249642 -0.249642)
							(end -0.2794 -0.1778)
						)
						(arc
							(start -0.2794 0.1778)
							(mid -0.249642 0.249642)
							(end -0.1778 0.2794)
						)
						(arc
							(start 0.1778 0.2794)
							(mid 0.249642 0.249642)
							(end 0.2794 0.1778)
						)
						(arc
							(start 0.2794 -0.1778)
							(mid 0.249642 -0.249642)
							(end 0.1778 -0.2794)
						)
					)
					(width 0)
					(fill yes)
				)
			)
		)
	)
	(footprint ""
		(layer "F.Cu")
		(at 230.251 -8.382 90)
		(property "Reference" "R953"
			(at 0 0 90)
			(layer "F.SilkS")
			(hide yes)
			(effects
				(font
					(size 1.27 1.27)
				)
			)
		)
		(property "Value" "0R2J-2-GP"
			(at 0.064008 -3.993896 90)
			(unlocked yes)
			(layer "F.Fab")
			(hide yes)
			(effects
				(font
					(size 1.016 1.016)
					(thickness 0.1524)
				)
			)
		)
		(property "Device Type" "R402H16"
			(at 0.064008 -5.517896 90)
			(unlocked yes)
			(layer "F.Fab")
			(hide yes)
			(effects
				(font
					(size 1.016 1.016)
					(thickness 0.1524)
				)
			)
		)
		(duplicate_pad_numbers_are_jumpers no)
		(fp_line
			(start 0.508 -0.9398)
			(end -0.508 -0.9398)
			(stroke
				(width 0.1524)
				(type default)
			)
			(layer "F.SilkS")
		)
		(fp_line
			(start -0.508 -0.9398)
			(end -0.508 0.9398)
			(stroke
				(width 0.1524)
				(type default)
			)
			(layer "F.SilkS")
		)
		(fp_rect
			(start -0.508 0.9398)
			(end 0.508 -0.9398)
			(stroke
				(width 0)
				(type default)
			)
			(fill no)
			(layer "F.CrtYd")
		)
		(fp_rect
			(start -0.508 0.9398)
			(end 0.508 -0.9398)
			(stroke
				(width 0)
				(type default)
			)
			(fill no)
			(layer "F.Fab")
		)
		(pad "1" smd custom
			(at 0 -0.4445 90)
			(size 0.1397 0.1397)
			(layers "F.Cu" "F.Mask" "F.Paste")
			(net "TWI_SCL2_R")
			(options
				(clearance outline)
				(anchor circle)
			)
			(primitives
				(gr_poly
					(pts
						(arc
							(start -0.1778 -0.2794)
							(mid -0.249642 -0.249642)
							(end -0.2794 -0.1778)
						)
						(arc
							(start -0.2794 0.1778)
							(mid -0.249642 0.249642)
							(end -0.1778 0.2794)
						)
						(arc
							(start 0.1778 0.2794)
							(mid 0.249642 0.249642)
							(end 0.2794 0.1778)
						)
						(arc
							(start 0.2794 -0.1778)
							(mid 0.249642 -0.249642)
							(end 0.1778 -0.2794)
						)
					)
					(width 0)
					(fill yes)
				)
			)
		)
		(pad "2" smd custom
			(at 0 0.4445 90)
			(size 0.1397 0.1397)
			(layers "F.Cu" "F.Mask" "F.Paste")
			(net "TWI_SCL2")
			(options
				(clearance outline)
				(anchor circle)
			)
			(primitives
				(gr_poly
					(pts
						(arc
							(start -0.1778 -0.2794)
							(mid -0.249642 -0.249642)
							(end -0.2794 -0.1778)
						)
						(arc
							(start -0.2794 0.1778)
							(mid -0.249642 0.249642)
							(end -0.1778 0.2794)
						)
						(arc
							(start 0.1778 0.2794)
							(mid 0.249642 0.249642)
							(end 0.2794 0.1778)
						)
						(arc
							(start 0.2794 -0.1778)
							(mid 0.249642 -0.249642)
							(end 0.1778 -0.2794)
						)
					)
					(width 0)
					(fill yes)
				)
			)
		)
	)
)
